#ISCELL
  mstr_symbols intel_corp_bpage *
  *
#CELL
  w_hdl test-pad-12p-1-gp-u *
  page270_i1
#ISCELL
  mstr_symbols gnd *
  page270_i10
#ISCELL
  mstr_symbols gnd *
  page270_i11
#CELL
  w_hdl test-pad-12p-1-gp-u *
  page270_i12
#CELL
  w_hdl test-pad-12p-1-gp-u *
  page270_i13
#ISCELL
  mstr_symbols gnd *
  page270_i14
#ISCELL
  mstr_symbols gnd *
  page270_i15
#CELL
  w_hdl test-pad-12p-1-gp-u *
  page270_i16
#CELL
  w_hdl test-pad-12p-1-gp-u *
  page270_i17
#CELL
  w_hdl test-pad-12p-1-gp-u *
  page270_i18
#ISCELL
  mstr_symbols gnd *
  page270_i19
#ISCELL
  mstr_symbols gnd *
  page270_i2
#ISCELL
  mstr_symbols gnd *
  page270_i20
#CELL
  w_hdl test-pad-12p-1-gp-u *
  page270_i21
#ISCELL
  mstr_symbols gnd *
  page270_i22
#ISCELL
  mstr_symbols gnd *
  page270_i23
#CELL
  w_hdl test-pad-12p-1-gp-u *
  page270_i24
#CELL
  w_hdl test-pad-12p-1-gp-u *
  page270_i3
#ISCELL
  mstr_symbols gnd *
  page270_i4
#CELL
  w_hdl test-pad-12p-1-gp-u *
  page270_i5
#CELL
  w_hdl test-pad-12p-1-gp-u *
  page270_i6
#ISCELL
  mstr_symbols gnd *
  page270_i7
#ISCELL
  mstr_symbols gnd *
  page270_i8
#CELL
  w_hdl test-pad-12p-1-gp-u *
  page270_i9
